FILE_TYPE = CONNECTIVITY;
{Allegro Design Entry HDL 16.6-p007 (v16-6-112F) 10/10/2012}
"PAGE_NUMBER" = 126;
0"NC";
1"GND\g";
2"P3V3_STBY\g";
3"GND\g";
4"P3V3_STBY\g";
5"GND\g";
6"P3V3_STBY\g";
7"P3V3_STBY\g";
8"FM_PCH_BMC_THERMTRIP_EXI_STRAP_N";
9"FM_OC_DETECT_EN_N";
10"IRQ_SML0_ALERT_N";
11"RST_RSMRST_DLY";
12"FM_FLASH_ATTACH_CFG_STRAP";
%"RES"
"2","(-6200,2775)","0","mstr_discrete","I12";
;
CDS_SEC"1"
MATERIAL"CHIP"
LOCATION"R1D35"
VALUE"4.75K"
WATTAGE"1/16W"
PART_NUMBER"G21796-072"
TOLERANCE"1%"
PACK_TYPE"0402"
ROOM"BMC_MISC"
CDS_LIB"mstr_discrete"
CDS_LOCATION"R1D35"
BOM_COST"SM_CONTROLLER"
SEC_TYPE"0402"
SEC"1";
"A"
$PN"1"6;
"B"
$PN"2"9;
%"FET_N"
"8","(-3625,3925)","0","mstr_discrete","I13";
;
CDS_SEC"1"
CDS_LOCATION"Q8E2"
LOCATION"Q8E2"
PART_NUMBER"C79254-001"
VALUE"2N7002"
MATERIAL"FET"
PACK_TYPE"SOT23LF"
CDS_LIB"mstr_discrete"
SEC"1"
SEC_TYPE"SOT23LF";
"GATE"
$PN"1"11;
"DRN"
$PN"3"10;
"SRC"
$PN"2"1;
%"GND"
"1","(-3625,3575)","0","mstr_symbols","I14";
;
VOLTAGE"0.0V"
HDL_POWER"GND"
ROOM"SB"
BODY_TYPE"PLUMBING"
CDS_LIB"mstr_symbols"
BOM_COST"SB"
SIZE"1B";
"A\NAC"1;
%"P3V3_STBY"
"1","(-3625,4650)","0","mstr_symbols","I16";
;
VOLTAGE"3.3V"
HDL_POWER"P3V3_STBY"
BODY_TYPE"PLUMBING"
CDS_LIB"mstr_symbols"
SIZE"1B";
"G\NAC"2;
%"RES"
"2","(-3625,4425)","0","mstr_discrete","I20";
;
CDS_SEC"1"
LOCATION"R8C9"
PART_NUMBER"G21796-072"
TOLERANCE"1%"
MATERIAL"CHIP"
WATTAGE"1/16W"
PACK_TYPE"0402"
VALUE"4.75K"
ROOM"BMC_MISC"
CDS_LIB"mstr_discrete"
BOM_COST"SM_CONTROLLER"
SEC_TYPE"0402"
SEC"1"
CDS_LOCATION"R8C9";
"A"
$PN"1"2;
"B"
$PN"2"10;
%"RES"
"2","(-4525,2725)","0","mstr_discrete","I22";
;
CDS_SEC"1"
CDS_LOCATION"R3P62"
PART_NUMBER"G21796-072"
MATERIAL"EMPTY"
WATTAGE"1/16W"
LOCATION"R3P62"
VALUE"4.75K"
TOLERANCE"1%"
PACK_TYPE"0402"
CDS_LIB"mstr_discrete"
SEC"1"
SEC_TYPE"0402";
"A"
$PN"1"4;
"B"
$PN"2"12;
%"RES"
"2","(-4525,2275)","0","mstr_discrete","I23";
;
CDS_SEC"1"
CDS_LOCATION"R3P64"
MATERIAL"EMPTY"
LOCATION"R3P64"
PART_NUMBER"G21796-026"
VALUE"1.00K"
TOLERANCE"1%"
PACK_TYPE"0402"
WATTAGE"1/16W"
CDS_LIB"mstr_discrete"
SEC_TYPE"0402"
SEC"1";
"A"
$PN"1"12;
"B"
$PN"2"3;
%"GND"
"1","(-4525,2050)","0","mstr_symbols","I24";
;
VOLTAGE"0.0V"
HDL_POWER"GND"
BODY_TYPE"PLUMBING"
SIZE"1B"
CDS_LIB"mstr_symbols";
"A\NAC"3;
%"P3V3_STBY"
"1","(-4525,2975)","0","mstr_symbols","I25";
;
VOLTAGE"3.3V"
HDL_POWER"P3V3_STBY"
CDS_LIB"mstr_symbols"
BODY_TYPE"PLUMBING"
SIZE"1B";
"G\NAC"4;
%"RES"
"2","(-6325,4300)","2","mstr_discrete","I27";
;
CDS_SEC"1"
LOCATION"R2N10"
MATERIAL"EMPTY"
PART_NUMBER"G21796-072"
PACK_TYPE"0402"
WATTAGE"1/16W"
TOLERANCE"1%"
VALUE"4.75K"
SEC_TYPE"0402"
BOM_COST"SYS_CLOCK"
SEC"1"
ROOM"DB1200ZL"
CDS_LIB"mstr_discrete"
CDS_LOCATION"R2N10";
"A"
$PN"1"7;
"B"
$PN"2"8;
%"GND"
"1","(-6200,2100)","0","mstr_symbols","I5";
;
VOLTAGE"0.0V"
HDL_POWER"GND"
ROOM"SB"
CDS_LIB"mstr_symbols"
BODY_TYPE"PLUMBING"
BOM_COST"SB"
SIZE"1B";
"A\NAC"5;
%"RES"
"2","(-6200,2350)","0","mstr_discrete","I6";
;
CDS_SEC"1"
PART_NUMBER"G21796-026"
MATERIAL"EMPTY"
LOCATION"R7D19"
VALUE"1.00K"
TOLERANCE"1%"
PACK_TYPE"0402"
WATTAGE"1/16W"
ROOM"SB"
CDS_LIB"mstr_discrete"
CDS_LOCATION"R7D19"
BOM_COST"SB"
SEC_TYPE"0402"
SEC"1";
"A"
$PN"1"9;
"B"
$PN"2"5;
%"P3V3_STBY"
"1","(-6200,3000)","0","mstr_symbols","I7";
;
VOLTAGE"3.3V"
HDL_POWER"P3V3_STBY"
SIZE"1B"
CDS_LIB"mstr_symbols"
BODY_TYPE"PLUMBING";
"G\NAC"6;
%"P3V3_STBY"
"1","(-6325,4575)","0","mstr_symbols","I9";
;
VOLTAGE"3.3V"
HDL_POWER"P3V3_STBY"
CDS_LIB"mstr_symbols"
SIZE"1B"
BODY_TYPE"PLUMBING";
"G\NAC"7;
END.
